(kicad_pcb
	(version 20260206)
	(generator "pcbnew")
	(generator_version "10.0")
	(general
		(thickness 1.6)
		(legacy_teardrops no)
	)
	(paper "A4")
	(title_block
		(title "Wiwynn_Tioga_Pass_MB.brd")
		(comment 1 "Tioga Pass / footprints 3079-3085 of 4770")
	)
	(layers
		(0 "F.Cu" signal "TOP")
		(4 "In1.Cu" signal "L2GND")
		(6 "In2.Cu" signal "L3")
		(8 "In3.Cu" signal "L4GND")
		(10 "In4.Cu" signal "L5")
		(12 "In5.Cu" signal "L6GND")
		(14 "In6.Cu" signal "L7VCC")
		(16 "In7.Cu" signal "L8VCC")
		(18 "In8.Cu" signal "L9GND")
		(20 "In9.Cu" signal "L10")
		(22 "In10.Cu" signal "L11GND")
		(24 "In11.Cu" signal "L12")
		(26 "In12.Cu" signal "L13GND")
		(2 "B.Cu" signal "BOTTOM")
		(9 "F.Adhes" user "F.Adhesive")
		(11 "B.Adhes" user "B.Adhesive")
		(13 "F.Paste" user "Package Geometry/Pastemask Top")
		(15 "B.Paste" user "Package Geometry/Pastemask Bottom")
		(5 "F.SilkS" user "Ref Des/Silkscreen Top")
		(7 "B.SilkS" user "Ref Des/Silkscreen Bottom")
		(1 "F.Mask" user "Board Geometry/Soldermask Top")
		(3 "B.Mask" user "Board Geometry/Soldermask Bottom")
		(17 "Dwgs.User" user "User.Drawings")
		(19 "Cmts.User" user "User.Comments")
		(21 "Eco1.User" user "User.Eco1")
		(23 "Eco2.User" user "User.Eco2")
		(25 "Edge.Cuts" user "Board Geometry/Outline")
		(27 "Margin" user)
		(31 "F.CrtYd" user "Package Geometry/Place Bound Top")
		(29 "B.CrtYd" user "Package Geometry/Place Bound Bottom")
		(35 "F.Fab" user "Ref Des/Assembly Top")
		(33 "B.Fab" user "Ref Des/Assembly Bottom")
	)
	(footprint ""
		(layer "B.Cu")
		(at 399.182336 -141.226286 180)
		(property "Reference" "C7B17"
			(at 0 0 0)
			(layer "B.SilkS")
			(hide yes)
			(effects
				(font
					(size 1.27 1.27)
				)
				(justify mirror)
			)
		)
		(property "Value" ""
			(at 0 0 0)
			(layer "B.Fab")
			(effects
				(font
					(size 1.27 1.27)
				)
				(justify mirror)
			)
		)
		(duplicate_pad_numbers_are_jumpers no)
		(fp_rect
			(start 0.4953 1.6002)
			(end -0.4953 -0.2032)
			(stroke
				(width 0)
				(type default)
			)
			(fill no)
			(layer "B.CrtYd")
		)
		(fp_line
			(start 0.4953 1.6002)
			(end 0.4953 -0.2032)
			(stroke
				(width 0.1)
				(type default)
			)
			(layer "B.Fab")
		)
		(fp_line
			(start 0.4953 -0.2032)
			(end -0.4953 -0.2032)
			(stroke
				(width 0.1)
				(type default)
			)
			(layer "B.Fab")
		)
		(fp_line
			(start -0.4953 1.6002)
			(end 0.4953 1.6002)
			(stroke
				(width 0.1)
				(type default)
			)
			(layer "B.Fab")
		)
		(fp_line
			(start -0.4953 -0.2032)
			(end -0.4953 1.6002)
			(stroke
				(width 0.1)
				(type default)
			)
			(layer "B.Fab")
		)
		(pad "1" smd rect
			(at 0 0)
			(size 0.762 0.889)
			(layers "B.Cu" "B.Mask" "B.Paste")
			(net "P1V05_PCH_STBY")
		)
		(pad "2" smd rect
			(at 0 1.397)
			(size 0.762 0.889)
			(layers "B.Cu" "B.Mask" "B.Paste")
			(net "GND")
		)
		(zone
			(layer "B.Cu")
			(hatch none 0.5)
			(connect_pads
				(clearance 0)
			)
			(min_thickness 0.25)
			(keepout
				(tracks not_allowed)
				(vias allowed)
				(pads allowed)
				(copperpour not_allowed)
				(footprints allowed)
			)
			(placement
				(enabled no)
				(sheetname "")
			)
			(fill
				(thermal_gap 0.5)
				(thermal_bridge_width 0.5)
				(island_removal_mode 0)
			)
			(polygon
				(pts
					(xy 398.801336 -142.178786) (xy 398.801336 -141.670786) (xy 399.563336 -141.670786) (xy 399.563336 -142.178786)
				)
			)
		)
	)
	(footprint ""
		(layer "B.Cu")
		(at 343.789 -83.566)
		(property "Reference" "R3P20"
			(at 0 0 0)
			(layer "B.SilkS")
			(hide yes)
			(effects
				(font
					(size 1.27 1.27)
				)
				(justify mirror)
			)
		)
		(property "Value" ""
			(at 0 0 0)
			(layer "B.Fab")
			(effects
				(font
					(size 1.27 1.27)
				)
				(justify mirror)
			)
		)
		(duplicate_pad_numbers_are_jumpers no)
		(fp_poly
			(pts
				(xy 0.2794 -0.1016) (xy -0.2794 -0.1016) (xy -0.2794 0.9906) (xy 0.2794 0.9906)
			)
			(stroke
				(width 0)
				(type default)
			)
			(fill no)
			(layer "B.CrtYd")
		)
		(fp_line
			(start -0.2794 -0.1016)
			(end 0.2794 -0.1016)
			(stroke
				(width 0.1)
				(type default)
			)
			(layer "B.Fab")
		)
		(fp_line
			(start -0.2794 0.9906)
			(end -0.2794 -0.1016)
			(stroke
				(width 0.1)
				(type default)
			)
			(layer "B.Fab")
		)
		(fp_line
			(start 0.2794 -0.1016)
			(end 0.2794 0.9906)
			(stroke
				(width 0.1)
				(type default)
			)
			(layer "B.Fab")
		)
		(fp_line
			(start 0.2794 0.9906)
			(end -0.2794 0.9906)
			(stroke
				(width 0.1)
				(type default)
			)
			(layer "B.Fab")
		)
		(pad "1" smd rect
			(at 0 0 180)
			(size 0.508 0.508)
			(layers "B.Cu" "B.Mask" "B.Paste")
			(net "PWRGD_PVCCIO_CPU0_R")
		)
		(pad "2" smd rect
			(at 0 0.889 180)
			(size 0.508 0.508)
			(layers "B.Cu" "B.Mask" "B.Paste")
			(net "PWRGD_PVCCIO_CPU0")
		)
		(zone
			(layer "B.Cu")
			(hatch none 0.5)
			(connect_pads
				(clearance 0)
			)
			(min_thickness 0.25)
			(keepout
				(tracks allowed)
				(vias not_allowed)
				(pads allowed)
				(copperpour not_allowed)
				(footprints allowed)
			)
			(placement
				(enabled no)
				(sheetname "")
			)
			(fill
				(thermal_gap 0.5)
				(thermal_bridge_width 0.5)
				(island_removal_mode 0)
			)
			(polygon
				(pts
					(xy 344.043 -83.312) (xy 343.535 -83.312) (xy 343.535 -82.931) (xy 344.043 -82.931)
				)
			)
		)
		(zone
			(layer "B.Cu")
			(hatch none 0.5)
			(connect_pads
				(clearance 0)
			)
			(min_thickness 0.25)
			(keepout
				(tracks not_allowed)
				(vias allowed)
				(pads allowed)
				(copperpour not_allowed)
				(footprints allowed)
			)
			(placement
				(enabled no)
				(sheetname "")
			)
			(fill
				(thermal_gap 0.5)
				(thermal_bridge_width 0.5)
				(island_removal_mode 0)
			)
			(polygon
				(pts
					(xy 344.043 -82.931) (xy 343.535 -82.931) (xy 343.535 -83.312) (xy 344.043 -83.312)
				)
			)
		)
	)
	(footprint ""
		(layer "B.Cu")
		(at 370.74348 -73.095358 90)
		(property "Reference" "C2R1"
			(at 0 0 90)
			(layer "B.SilkS")
			(hide yes)
			(effects
				(font
					(size 1.27 1.27)
				)
				(justify mirror)
			)
		)
		(property "Value" ""
			(at 0 0 90)
			(layer "B.Fab")
			(effects
				(font
					(size 1.27 1.27)
				)
				(justify mirror)
			)
		)
		(duplicate_pad_numbers_are_jumpers no)
		(fp_rect
			(start 0.2794 0.9144)
			(end -0.2794 -0.1143)
			(stroke
				(width 0)
				(type default)
			)
			(fill no)
			(layer "B.CrtYd")
		)
		(fp_line
			(start 0.2794 -0.1143)
			(end -0.2794 -0.1143)
			(stroke
				(width 0.1)
				(type default)
			)
			(layer "B.Fab")
		)
		(fp_line
			(start -0.2794 -0.1143)
			(end -0.2794 0.9144)
			(stroke
				(width 0.1)
				(type default)
			)
			(layer "B.Fab")
		)
		(fp_line
			(start 0.2794 0.9144)
			(end 0.2794 -0.1143)
			(stroke
				(width 0.1)
				(type default)
			)
			(layer "B.Fab")
		)
		(fp_line
			(start -0.2794 0.9144)
			(end 0.2794 0.9144)
			(stroke
				(width 0.1)
				(type default)
			)
			(layer "B.Fab")
		)
		(pad "1" smd custom
			(at 0 0)
			(size 0.10414 0.10414)
			(layers "B.Cu" "B.Mask" "B.Paste")
			(net "P3V3_STBY")
			(options
				(clearance outline)
				(anchor circle)
			)
			(primitives
				(gr_poly
					(pts
						(xy -0.20828 -0.08636) (xy -0.20828 0.08636) (xy -0.08636 0.20828) (xy 0.086614 0.20828) (xy 0.20828 0.086614)
						(xy 0.20828 -0.08636) (xy 0.08636 -0.20828) (xy -0.08636 -0.20828)
					)
					(width 0)
					(fill yes)
				)
			)
		)
		(pad "2" smd custom
			(at 0 0.8001)
			(size 0.10414 0.10414)
			(layers "B.Cu" "B.Mask" "B.Paste")
			(net "GND")
			(options
				(clearance outline)
				(anchor circle)
			)
			(primitives
				(gr_poly
					(pts
						(xy -0.20828 -0.08636) (xy -0.20828 0.08636) (xy -0.08636 0.20828) (xy 0.086614 0.20828) (xy 0.20828 0.086614)
						(xy 0.20828 -0.08636) (xy 0.08636 -0.20828) (xy -0.08636 -0.20828)
					)
					(width 0)
					(fill yes)
				)
			)
		)
		(zone
			(layer "B.Cu")
			(hatch none 0.5)
			(connect_pads
				(clearance 0)
			)
			(min_thickness 0.25)
			(keepout
				(tracks not_allowed)
				(vias allowed)
				(pads allowed)
				(copperpour not_allowed)
				(footprints allowed)
			)
			(placement
				(enabled no)
				(sheetname "")
			)
			(fill
				(thermal_gap 0.5)
				(thermal_bridge_width 0.5)
				(island_removal_mode 0)
			)
			(polygon
				(pts
					(xy 370.95303 -73.182988) (xy 371.33403 -73.182988) (xy 371.33403 -73.007728) (xy 370.95303 -73.007474)
				)
			)
		)
		(zone
			(layer "B.Cu")
			(hatch none 0.5)
			(connect_pads
				(clearance 0)
			)
			(min_thickness 0.25)
			(keepout
				(tracks allowed)
				(vias not_allowed)
				(pads allowed)
				(copperpour not_allowed)
				(footprints allowed)
			)
			(placement
				(enabled no)
				(sheetname "")
			)
			(fill
				(thermal_gap 0.5)
				(thermal_bridge_width 0.5)
				(island_removal_mode 0)
			)
			(polygon
				(pts
					(xy 370.95303 -73.182988) (xy 371.33403 -73.182988) (xy 371.33403 -73.007728) (xy 370.95303 -73.007474)
				)
			)
		)
	)
	(footprint ""
		(layer "B.Cu")
		(at 88.214708 -125.99162 90)
		(property "Reference" "SH7L1"
			(at 0 0 90)
			(layer "B.SilkS")
			(hide yes)
			(effects
				(font
					(size 1.27 1.27)
				)
				(justify mirror)
			)
		)
		(property "Value" ""
			(at 0 0 90)
			(layer "B.Fab")
			(effects
				(font
					(size 1.27 1.27)
				)
				(justify mirror)
			)
		)
		(duplicate_pad_numbers_are_jumpers no)
		(fp_poly
			(pts
				(xy 0.1651 -0.0508) (xy 0.1651 0.5842) (xy -0.1651 0.5842) (xy -0.1651 -0.0508)
			)
			(stroke
				(width 0)
				(type default)
			)
			(fill no)
			(layer "B.CrtYd")
		)
		(fp_line
			(start 0.1651 -0.0508)
			(end -0.1651 -0.0508)
			(stroke
				(width 0.1)
				(type default)
			)
			(layer "B.Fab")
		)
		(fp_line
			(start -0.1651 -0.0508)
			(end -0.1651 0.5842)
			(stroke
				(width 0.1)
				(type default)
			)
			(layer "B.Fab")
		)
		(fp_line
			(start 0.1651 0.5842)
			(end 0.1651 -0.0508)
			(stroke
				(width 0.1)
				(type default)
			)
			(layer "B.Fab")
		)
		(fp_line
			(start -0.1651 0.5842)
			(end 0.1651 0.5842)
			(stroke
				(width 0.1)
				(type default)
			)
			(layer "B.Fab")
		)
		(pad "1" smd custom
			(at 0 0 90)
			(size 0.0762 0.0762)
			(layers "B.Cu" "B.Mask" "B.Paste")
			(net "VSENSE_PVDDQ_KLM_N")
			(options
				(clearance outline)
				(anchor circle)
			)
			(primitives
				(gr_poly
					(pts
						(arc
							(start -0.1524 0.10795)
							(mid -0.098518 0.130268)
							(end -0.0762 0.18415)
						)
						(xy -0.0762 0.22225) (xy 0.0762 0.22225)
						(arc
							(start 0.0762 0.18415)
							(mid 0.098518 0.130268)
							(end 0.1524 0.10795)
						)
						(xy 0.1524 -0.22225) (xy -0.1524 -0.22225)
					)
					(width 0)
					(fill yes)
				)
			)
		)
		(pad "2" smd custom
			(at 0 0.5334 270)
			(size 0.0762 0.0762)
			(layers "B.Cu" "B.Mask" "B.Paste")
			(net "GND")
			(options
				(clearance outline)
				(anchor circle)
			)
			(primitives
				(gr_poly
					(pts
						(arc
							(start -0.1524 0.10795)
							(mid -0.098518 0.130268)
							(end -0.0762 0.18415)
						)
						(xy -0.0762 0.22225) (xy 0.0762 0.22225)
						(arc
							(start 0.0762 0.18415)
							(mid 0.098518 0.130268)
							(end 0.1524 0.10795)
						)
						(xy 0.1524 -0.22225) (xy -0.1524 -0.22225)
					)
					(width 0)
					(fill yes)
				)
			)
		)
	)
	(footprint ""
		(layer "B.Cu")
		(at 26.0096 -30.988)
		(property "Reference" "R9T9"
			(at 0 0 0)
			(layer "B.SilkS")
			(hide yes)
			(effects
				(font
					(size 1.27 1.27)
				)
				(justify mirror)
			)
		)
		(property "Value" ""
			(at 0 0 0)
			(layer "B.Fab")
			(effects
				(font
					(size 1.27 1.27)
				)
				(justify mirror)
			)
		)
		(duplicate_pad_numbers_are_jumpers no)
		(fp_rect
			(start -0.2794 0.9906)
			(end 0.2794 -0.1016)
			(stroke
				(width 0)
				(type default)
			)
			(fill no)
			(layer "B.CrtYd")
		)
		(fp_line
			(start -0.2794 -0.1016)
			(end 0.2794 -0.1016)
			(stroke
				(width 0.1)
				(type default)
			)
			(layer "B.Fab")
		)
		(fp_line
			(start -0.2794 0.9906)
			(end -0.2794 -0.1016)
			(stroke
				(width 0.1)
				(type default)
			)
			(layer "B.Fab")
		)
		(fp_line
			(start 0.2794 -0.1016)
			(end 0.2794 0.9906)
			(stroke
				(width 0.1)
				(type default)
			)
			(layer "B.Fab")
		)
		(fp_line
			(start 0.2794 0.9906)
			(end -0.2794 0.9906)
			(stroke
				(width 0.1)
				(type default)
			)
			(layer "B.Fab")
		)
		(pad "1" smd rect
			(at 0 0 180)
			(size 0.508 0.508)
			(layers "B.Cu" "B.Mask" "B.Paste")
			(net "P12V_PSU")
		)
		(pad "2" smd rect
			(at 0 0.889 180)
			(size 0.508 0.508)
			(layers "B.Cu" "B.Mask" "B.Paste")
			(net "FM_MATED_IN_N")
		)
		(zone
			(layer "B.Cu")
			(hatch none 0.5)
			(connect_pads
				(clearance 0)
			)
			(min_thickness 0.25)
			(keepout
				(tracks not_allowed)
				(vias allowed)
				(pads allowed)
				(copperpour not_allowed)
				(footprints allowed)
			)
			(placement
				(enabled no)
				(sheetname "")
			)
			(fill
				(thermal_gap 0.5)
				(thermal_bridge_width 0.5)
				(island_removal_mode 0)
			)
			(polygon
				(pts
					(xy 25.7556 -30.353) (xy 26.2636 -30.353) (xy 26.2636 -30.734) (xy 25.7556 -30.734)
				)
			)
		)
		(zone
			(layer "B.Cu")
			(hatch none 0.5)
			(connect_pads
				(clearance 0)
			)
			(min_thickness 0.25)
			(keepout
				(tracks allowed)
				(vias not_allowed)
				(pads allowed)
				(copperpour not_allowed)
				(footprints allowed)
			)
			(placement
				(enabled no)
				(sheetname "")
			)
			(fill
				(thermal_gap 0.5)
				(thermal_bridge_width 0.5)
				(island_removal_mode 0)
			)
			(polygon
				(pts
					(xy 25.7556 -30.353) (xy 26.2636 -30.353) (xy 26.2636 -30.734) (xy 25.7556 -30.734)
				)
			)
		)
	)
	(footprint ""
		(layer "B.Cu")
		(at 24.1046 -84.5312 90)
		(property "Reference" "CR9P2"
			(at 0 0 90)
			(layer "B.SilkS")
			(hide yes)
			(effects
				(font
					(size 1.27 1.27)
				)
				(justify mirror)
			)
		)
		(property "Value" ""
			(at 0 0 90)
			(layer "B.Fab")
			(effects
				(font
					(size 1.27 1.27)
				)
				(justify mirror)
			)
		)
		(duplicate_pad_numbers_are_jumpers no)
		(fp_line
			(start -0.623062 -0.352806)
			(end -0.623062 0.770636)
			(stroke
				(width 0.1524)
				(type default)
			)
			(layer "B.SilkS")
		)
		(fp_line
			(start -0.623062 0.770636)
			(end -1.103884 1.603502)
			(stroke
				(width 0.1524)
				(type default)
			)
			(layer "B.SilkS")
		)
		(fp_line
			(start -1.103884 0.770636)
			(end -0.14224 0.770636)
			(stroke
				(width 0.1524)
				(type default)
			)
			(layer "B.SilkS")
		)
		(fp_line
			(start -0.14224 1.603502)
			(end -0.623062 0.770636)
			(stroke
				(width 0.1524)
				(type default)
			)
			(layer "B.SilkS")
		)
		(fp_line
			(start -0.623062 1.603502)
			(end -0.14224 1.603502)
			(stroke
				(width 0.1524)
				(type default)
			)
			(layer "B.SilkS")
		)
		(fp_line
			(start -1.103884 1.603502)
			(end -0.623062 1.603502)
			(stroke
				(width 0.1524)
				(type default)
			)
			(layer "B.SilkS")
		)
		(fp_line
			(start -0.623062 2.515108)
			(end -0.623062 1.603502)
			(stroke
				(width 0.1524)
				(type default)
			)
			(layer "B.SilkS")
		)
		(fp_poly
			(pts
				(xy 0.67437 0.24384) (xy 0.67437 2.04216) (xy -0.67437 2.04216) (xy -0.67437 0.24384)
			)
			(stroke
				(width 0)
				(type default)
			)
			(fill no)
			(layer "B.CrtYd")
		)
		(fp_line
			(start 0.67437 0.24384)
			(end 0.67437 2.04216)
			(stroke
				(width 0.1)
				(type default)
			)
			(layer "B.Fab")
		)
		(fp_line
			(start -0.67437 0.24384)
			(end 0.67437 0.24384)
			(stroke
				(width 0.1)
				(type default)
			)
			(layer "B.Fab")
		)
		(fp_line
			(start -0.623062 0.770636)
			(end -0.623062 -0.352806)
			(stroke
				(width 0.1)
				(type default)
			)
			(layer "B.Fab")
		)
		(fp_line
			(start -0.623062 0.770636)
			(end -1.103884 1.603502)
			(stroke
				(width 0.1)
				(type default)
			)
			(layer "B.Fab")
		)
		(fp_line
			(start -1.103884 0.770636)
			(end -0.14224 0.770636)
			(stroke
				(width 0.1)
				(type default)
			)
			(layer "B.Fab")
		)
		(fp_line
			(start -0.14224 1.603502)
			(end -0.623062 0.770636)
			(stroke
				(width 0.1)
				(type default)
			)
			(layer "B.Fab")
		)
		(fp_line
			(start -0.623062 1.603502)
			(end -0.623062 2.515108)
			(stroke
				(width 0.1)
				(type default)
			)
			(layer "B.Fab")
		)
		(fp_line
			(start -1.103884 1.603502)
			(end -0.14224 1.603502)
			(stroke
				(width 0.1)
				(type default)
			)
			(layer "B.Fab")
		)
		(fp_line
			(start 0.67437 2.04216)
			(end -0.67437 2.04216)
			(stroke
				(width 0.1)
				(type default)
			)
			(layer "B.Fab")
		)
		(fp_line
			(start -0.67437 2.04216)
			(end -0.67437 0.24384)
			(stroke
				(width 0.1)
				(type default)
			)
			(layer "B.Fab")
		)
		(pad "1" smd rect
			(at 0 0 270)
			(size 0.4064 1.016)
			(layers "B.Cu" "B.Mask" "B.Paste")
			(net "FM_UV_ADR_TRIGGER_N")
		)
		(pad "2" smd rect
			(at 0 2.286 270)
			(size 0.4064 1.016)
			(layers "B.Cu" "B.Mask" "B.Paste")
			(net "FM_DISABLE_FAN_N")
		)
	)
	(footprint ""
		(layer "B.Cu")
		(at 107.8611 -8.1534 90)
		(property "Reference" "C7U2"
			(at -1.848866 0.752348 90)
			(unlocked yes)
			(layer "B.SilkS")
			(effects
				(font
					(size 1.27 0.9652)
					(thickness 0.1524)
				)
				(justify mirror)
			)
		)
		(property "Value" ""
			(at 0 0 90)
			(layer "B.Fab")
			(effects
				(font
					(size 1.27 1.27)
				)
				(justify mirror)
			)
		)
		(duplicate_pad_numbers_are_jumpers no)
		(fp_rect
			(start 0.500126 1.598422)
			(end -0.500126 -0.201422)
			(stroke
				(width 0)
				(type default)
			)
			(fill no)
			(layer "B.CrtYd")
		)
		(fp_line
			(start 0.500126 -0.201422)
			(end -0.500126 -0.201422)
			(stroke
				(width 0.1)
				(type default)
			)
			(layer "B.Fab")
		)
		(fp_line
			(start -0.500126 -0.201422)
			(end -0.500126 1.598422)
			(stroke
				(width 0.1)
				(type default)
			)
			(layer "B.Fab")
		)
		(fp_line
			(start 0.500126 1.598422)
			(end 0.500126 -0.201422)
			(stroke
				(width 0.1)
				(type default)
			)
			(layer "B.Fab")
		)
		(fp_line
			(start -0.500126 1.598422)
			(end 0.500126 1.598422)
			(stroke
				(width 0.1)
				(type default)
			)
			(layer "B.Fab")
		)
		(pad "1" smd rect
			(at 0 0)
			(size 0.889 0.9906)
			(layers "B.Cu" "B.Mask" "B.Paste")
			(net "PVDDQ_GHJ")
		)
		(pad "2" smd rect
			(at 0 1.397)
			(size 0.889 0.9906)
			(layers "B.Cu" "B.Mask" "B.Paste")
			(net "GND")
		)
		(zone
			(layer "B.Cu")
			(hatch none 0.5)
			(connect_pads
				(clearance 0)
			)
			(min_thickness 0.25)
			(keepout
				(tracks allowed)
				(vias not_allowed)
				(pads allowed)
				(copperpour not_allowed)
				(footprints allowed)
			)
			(placement
				(enabled no)
				(sheetname "")
			)
			(fill
				(thermal_gap 0.5)
				(thermal_bridge_width 0.5)
				(island_removal_mode 0)
			)
			(polygon
				(pts
					(xy 108.8136 -8.6487) (xy 108.3056 -8.6487) (xy 108.3056 -7.6581) (xy 108.8136 -7.6581)
				)
			)
		)
		(zone
			(layer "B.Cu")
			(hatch none 0.5)
			(connect_pads
				(clearance 0)
			)
			(min_thickness 0.25)
			(keepout
				(tracks not_allowed)
				(vias allowed)
				(pads allowed)
				(copperpour not_allowed)
				(footprints allowed)
			)
			(placement
				(enabled no)
				(sheetname "")
			)
			(fill
				(thermal_gap 0.5)
				(thermal_bridge_width 0.5)
				(island_removal_mode 0)
			)
			(polygon
				(pts
					(xy 108.8136 -8.6487) (xy 108.3056 -8.6487) (xy 108.3056 -7.6581) (xy 108.8136 -7.6581)
				)
			)
		)
	)
)
